#ISCELL
  pure_quanta quanta_title_block_c *
  *
#CELL
  pure_quanta genoa_sp5 *
  page58_i1
#CELL
  pure_quanta genoa_sp5 *
  page58_i12
#CELL
  pure_quanta genoa_sp5 *
  page58_i15
#ISCELL
  pure_quanta_power universal_gnd *
  page58_i18
#ISCELL
  pure_quanta_power universal_gnd *
  page58_i19
#ISCELL
  pure_quanta_power universal_gnd *
  page58_i20
#ISCELL
  pure_quanta_power universal_gnd *
  page58_i21
#ISCELL
  pure_quanta_power universal_gnd *
  page58_i22
#ISCELL
  pure_quanta_power universal_gnd *
  page58_i23
#ISCELL
  pure_quanta_power universal_gnd *
  page58_i24
#ISCELL
  pure_quanta_power universal_gnd *
  page58_i25
#ISCELL
  pure_quanta_power universal_gnd *
  page58_i26
#ISCELL
  pure_quanta_power universal_gnd *
  page58_i27
#ISCELL
  pure_quanta_power universal_gnd *
  page58_i28
#ISCELL
  pure_quanta_power universal_gnd *
  page58_i29
#CELL
  pure_quanta genoa_sp5 *
  page58_i3
#CELL
  pure_quanta genoa_sp5 *
  page58_i6
#CELL
  pure_quanta genoa_sp5 *
  page58_i9
